# Bryce Canyon_LED_Board_Stackup.xlsx — 16347-SC (pcb-stackup)
|  |  |  |  |  |  | Version |  |  |  |  |  |  |  |
| Board Number: |  | 16347-SC |  |  |  | 01 |  |  |  |  |  |  |  |
| Project name: |  | Bryce Canyon |  |  |  |  |  |  |  |  |  |  |  |
| Model Name: |  | LED Board |  |  |  |  |  |  |  |  |  |  |  |
| Layer Count: |  | 2 Layer |  |  |  |  |  |  |  |  |  |  |  |
| Date: |  | 2017-02-06 00:00:00 |  |  |  |  |  |  |  |  |  |  |  |
| Medium Loss Material: |  | IT150G / NPG150N(Tg : 150/Td : 350) |  |  |  |  |  |  |  | Single Ended Type(mil) |  |  |  |
| Golden Finger(Y/N): |  | N |  |  |  |  |  |  | Imp | 50 |  |  |  |
| Customer: |  | <name> |  |  |  |  |  |  | Variation | Inner/Outer+/-10% |  |  |  |
| EE engineer |  | <name> |  |  |  |  |  |  | Bus | MISC. |  |  |  |
| SI Engineer |  | <name> |  |  |  |  |  |  |  |  |  |  |  |
|  |  |  |  |  |  |  |  |  | Type | SE |  |  |  |
| Layer |  |  | Thickness |  | Glass/Copper Style | Er |  | Df(1G) | Layers | 1,2 |  |  |  |
|  |  | Cu oz | Wiwynn |  |  | Wiwynn |  |  |  | Wiwynn |  |  |  |
|  | Mask |  | 0.5 |  |  | 3.4 |  |  |  | Width | Imp | Width | Imp |
| Top | Signal/GND | 0.5 oz+plating | 1.9 |  |  |  |  |  | S1 | 20(L1) | 49.57 |  |  |
|  | Core |  | 34.5 |  |  | 4.5 |  |  |  |  |  |  |  |
| Bottom | Signal/GND | 0.5 oz+plating | 1.9 | 0 | 0 |  |  |  | S2 | 20(L2) | 49.57 |  |  |
|  | Mask |  | 0.5 | 0 |  | 3.4 | 0 | 0 |  |  |  |  |  |
| Thickness requirement: 1.0 ± 10% mm |  | mil | 39.3 |  |  |  |  |  |  |  |  |  |  |
|  |  | mm | 0.9982219964439929 |  |  |  |  |  |  |  |  |  |  |
| Note: | 1. Unit is mil |  |  |  |  |  |  |  |  |  |  |  |  |
|  | 2. The total thickness includes trace and solder mask |  |  |  |  |  |  |  |  |  |  |  |  |
|  | 3. Minimum hole copper thickness is 1.0 mil |  |  |  |  |  |  |  |  |  |  |  |  |
|  | 4. Minimum surface copper thickness 1.5 mil |  |  |  |  |  |  |  |  |  |  |  |  |
|  | 5. If there is no controlled impedance line described as the stackup in the gerber file, PCB supplier can ignore this kind of impedance control directly, but need to inform Wiwynn. |  |  |  |  |  |  |  |  |  |  |  |  |
|  | 6. Impedance Cpk requirement: >=1.33 (Value should be provided in the first article report) |  |  |  |  |  |  |  |  |  |  |  |  |
